(kicad_pcb
	(version 20260206)
	(generator "pcbnew")
	(generator_version "10.0")
	(general
		(thickness 1.6)
		(legacy_teardrops no)
	)
	(paper "A4")
	(title_block
		(title "04192023_DAF0TMB3IC0_F0TG_MB_C_brd_V02_OCP.brd")
		(comment 1 "Grand Teton / footprints 6347-6353 of 8354")
	)
	(layers
		(0 "F.Cu" signal "TOP")
		(4 "In1.Cu" signal "GND")
		(6 "In2.Cu" signal "IN1")
		(8 "In3.Cu" signal "GND1")
		(10 "In4.Cu" signal "IN2")
		(12 "In5.Cu" signal "GND2")
		(14 "In6.Cu" signal "IN3")
		(16 "In7.Cu" signal "GND3")
		(18 "In8.Cu" signal "VCC")
		(20 "In9.Cu" signal "VCC1")
		(22 "In10.Cu" signal "GND4")
		(24 "In11.Cu" signal "IN4")
		(26 "In12.Cu" signal "GND5")
		(28 "In13.Cu" signal "IN5")
		(30 "In14.Cu" signal "GND6")
		(32 "In15.Cu" signal "IN6")
		(34 "In16.Cu" signal "GND7")
		(2 "B.Cu" signal "BOTTOM")
		(9 "F.Adhes" user "F.Adhesive")
		(11 "B.Adhes" user "B.Adhesive")
		(13 "F.Paste" user "Package Geometry/Pastemask Top")
		(15 "B.Paste" user "Package Geometry/Pastemask Bottom")
		(5 "F.SilkS" user "Ref Des/Silkscreen Top")
		(7 "B.SilkS" user "Ref Des/Silkscreen Bottom")
		(1 "F.Mask" user "Board Geometry/Soldermask Top")
		(3 "B.Mask" user "Board Geometry/Soldermask Bottom")
		(17 "Dwgs.User" user "User.Drawings")
		(19 "Cmts.User" user "User.Comments")
		(21 "Eco1.User" user "User.Eco1")
		(23 "Eco2.User" user "User.Eco2")
		(25 "Edge.Cuts" user "Board Geometry/Outline")
		(27 "Margin" user)
		(31 "F.CrtYd" user "Package Geometry/Place Bound Top")
		(29 "B.CrtYd" user "Package Geometry/Place Bound Bottom")
		(35 "F.Fab" user "Ref Des/Assembly Top")
		(33 "B.Fab" user "Ref Des/Assembly Bottom")
	)
	(footprint ""
		(layer "B.Cu")
		(at 231.138476 -236.074204 90)
		(property "Reference" "U213"
			(at -2.063242 -3.25882 270)
			(unlocked yes)
			(layer "B.SilkS")
			(effects
				(font
					(size 0.7874 0.5842)
					(thickness 0.1524)
				)
				(justify left mirror)
			)
		)
		(property "Value" ""
			(at 0 0 90)
			(layer "B.Fab")
			(effects
				(font
					(size 1.27 1.27)
				)
				(justify mirror)
			)
		)
		(duplicate_pad_numbers_are_jumpers no)
		(fp_line
			(start 1.781302 -1.012698)
			(end -1.781302 -1.012698)
			(stroke
				(width 0.1524)
				(type default)
			)
			(layer "B.SilkS")
		)
		(fp_line
			(start -1.781302 -1.012698)
			(end -1.781302 1.012698)
			(stroke
				(width 0.1524)
				(type default)
			)
			(layer "B.SilkS")
		)
		(fp_line
			(start 1.781302 1.012698)
			(end 1.781302 -1.012698)
			(stroke
				(width 0.1524)
				(type default)
			)
			(layer "B.SilkS")
		)
		(fp_line
			(start 0 1.012698)
			(end 1.781302 1.012698)
			(stroke
				(width 0.1524)
				(type default)
			)
			(layer "B.SilkS")
		)
		(fp_line
			(start -1.781302 1.012698)
			(end 0 1.012698)
			(stroke
				(width 0.1524)
				(type default)
			)
			(layer "B.SilkS")
		)
		(fp_poly
			(pts
				(xy 1.214374 -1.333754) (xy 1.187704 -2.469134) (xy 0.290068 -1.993646)
			)
			(stroke
				(width 0)
				(type default)
			)
			(fill yes)
			(layer "B.SilkS")
		)
		(fp_line
			(start 1.500124 -0.999998)
			(end -1.500124 -0.999998)
			(stroke
				(width 0.1)
				(type default)
			)
			(layer "B.Fab")
		)
		(fp_line
			(start -1.500124 -0.999998)
			(end -1.500124 0.999998)
			(stroke
				(width 0.1)
				(type default)
			)
			(layer "B.Fab")
		)
		(fp_line
			(start 1.500124 0.999998)
			(end 1.500124 -0.999998)
			(stroke
				(width 0.1)
				(type default)
			)
			(layer "B.Fab")
		)
		(fp_line
			(start 0 0.999998)
			(end 1.500124 0.999998)
			(stroke
				(width 0.1)
				(type default)
			)
			(layer "B.Fab")
		)
		(fp_line
			(start -1.500124 0.999998)
			(end 0 0.999998)
			(stroke
				(width 0.1)
				(type default)
			)
			(layer "B.Fab")
		)
		(fp_poly
			(pts
				(xy 2.9972 -1.258062) (xy 2.9972 -0.242062) (xy 1.9812 -0.750062)
			)
			(stroke
				(width 0)
				(type default)
			)
			(fill yes)
			(layer "B.Fab")
		)
		(pad "1" smd rect
			(at 1.374902 -0.750062)
			(size 0.254 0.5588)
			(layers "B.Cu" "B.Mask" "B.Paste")
			(net "SMB_APML_CPU0_R_SDA")
		)
		(pad "2" smd rect
			(at 1.374902 -0.249936)
			(size 0.254 0.5588)
			(layers "B.Cu" "B.Mask" "B.Paste")
			(net "SMB_CPU0_CPU1_APML_MUX1_SDA")
		)
		(pad "3" smd rect
			(at 1.374902 0.249936)
			(size 0.254 0.5588)
			(layers "B.Cu" "B.Mask" "B.Paste")
			(net "SMB_CPU0_CPU1_APML_MUX1_SCL")
		)
		(pad "4" smd rect
			(at 1.374902 0.750062)
			(size 0.254 0.5588)
			(layers "B.Cu" "B.Mask" "B.Paste")
			(net "SMB_APML_CPU0_R_SCL")
		)
		(pad "5" smd rect
			(at -1.374902 0.750062)
			(size 0.254 0.5588)
			(layers "B.Cu" "B.Mask" "B.Paste")
			(net "PVDD18_S5_P0")
		)
		(pad "6" smd rect
			(at -1.374902 0.249936)
			(size 0.254 0.5588)
			(layers "B.Cu" "B.Mask" "B.Paste")
			(net "SMB_APML_CPU1_R_SCL")
		)
		(pad "7" smd rect
			(at -1.374902 -0.249936)
			(size 0.254 0.5588)
			(layers "B.Cu" "B.Mask" "B.Paste")
			(net "I3C_MUX_CPU0_VIO")
		)
		(pad "8" smd rect
			(at -1.374902 -0.750062)
			(size 0.254 0.5588)
			(layers "B.Cu" "B.Mask" "B.Paste")
			(net "SMB_APML_CPU1_R_SDA")
		)
		(pad "9" smd circle
			(at 0 0 270)
			(size 0 0)
			(layers "B.Cu" "B.Mask" "B.Paste")
			(net "GND")
		)
		(zone
			(layer "B.Cu")
			(hatch none 0.5)
			(connect_pads
				(clearance 0)
			)
			(min_thickness 0.25)
			(keepout
				(tracks not_allowed)
				(vias allowed)
				(pads allowed)
				(copperpour not_allowed)
				(footprints allowed)
			)
			(placement
				(enabled no)
				(sheetname "")
			)
			(fill
				(thermal_gap 0.5)
				(thermal_bridge_width 0.5)
				(island_removal_mode 0)
			)
			(polygon
				(pts
					(xy 232.129076 -237.115604) (xy 230.147876 -237.115604) (xy 230.147876 -236.556804) (xy 230.325676 -236.556804)
					(xy 230.325676 -236.887004) (xy 231.951276 -236.887004) (xy 231.951276 -235.261404) (xy 230.325676 -235.261404)
					(xy 230.325676 -236.531404) (xy 230.147876 -236.531404) (xy 230.147876 -235.032804) (xy 232.129076 -235.032804)
				)
			)
		)
	)
	(footprint ""
		(layer "B.Cu")
		(at 155.02001 -16.851122 -90)
		(property "Reference" "R3004"
			(at 0 0 90)
			(layer "B.SilkS")
			(hide yes)
			(effects
				(font
					(size 1.27 1.27)
				)
				(justify mirror)
			)
		)
		(property "Value" ""
			(at 0 0 90)
			(layer "B.Fab")
			(effects
				(font
					(size 1.27 1.27)
				)
				(justify mirror)
			)
		)
		(duplicate_pad_numbers_are_jumpers no)
		(fp_line
			(start -0.7874 0.4064)
			(end 0.7874 0.4064)
			(stroke
				(width 0.1524)
				(type default)
			)
			(layer "B.SilkS")
		)
		(fp_line
			(start 0.7874 0.4064)
			(end 0.7874 -0.4064)
			(stroke
				(width 0.1524)
				(type default)
			)
			(layer "B.SilkS")
		)
		(fp_line
			(start -0.7874 -0.4064)
			(end -0.7874 0.4064)
			(stroke
				(width 0.1524)
				(type default)
			)
			(layer "B.SilkS")
		)
		(fp_line
			(start 0.7874 -0.4064)
			(end -0.7874 -0.4064)
			(stroke
				(width 0.1524)
				(type default)
			)
			(layer "B.SilkS")
		)
		(fp_line
			(start -0.67945 0.3048)
			(end -0.120396 0.3048)
			(stroke
				(width 0.1)
				(type default)
			)
			(layer "B.Fab")
		)
		(fp_line
			(start -0.120396 0.3048)
			(end -0.120396 0.2794)
			(stroke
				(width 0.1)
				(type default)
			)
			(layer "B.Fab")
		)
		(fp_line
			(start 0.12065 0.3048)
			(end 0.67945 0.3048)
			(stroke
				(width 0.1)
				(type default)
			)
			(layer "B.Fab")
		)
		(fp_line
			(start 0.67945 0.3048)
			(end 0.67945 -0.305054)
			(stroke
				(width 0.1)
				(type default)
			)
			(layer "B.Fab")
		)
		(fp_line
			(start -0.120396 0.2794)
			(end 0.12065 0.2794)
			(stroke
				(width 0.1)
				(type default)
			)
			(layer "B.Fab")
		)
		(fp_line
			(start 0.12065 0.2794)
			(end 0.12065 0.3048)
			(stroke
				(width 0.1)
				(type default)
			)
			(layer "B.Fab")
		)
		(fp_line
			(start -0.12065 -0.2794)
			(end -0.12065 -0.3048)
			(stroke
				(width 0.1)
				(type default)
			)
			(layer "B.Fab")
		)
		(fp_line
			(start 0.12065 -0.2794)
			(end -0.12065 -0.2794)
			(stroke
				(width 0.1)
				(type default)
			)
			(layer "B.Fab")
		)
		(fp_line
			(start -0.67945 -0.3048)
			(end -0.67945 0.3048)
			(stroke
				(width 0.1)
				(type default)
			)
			(layer "B.Fab")
		)
		(fp_line
			(start -0.12065 -0.3048)
			(end -0.67945 -0.3048)
			(stroke
				(width 0.1)
				(type default)
			)
			(layer "B.Fab")
		)
		(fp_line
			(start 0.12065 -0.305054)
			(end 0.12065 -0.2794)
			(stroke
				(width 0.1)
				(type default)
			)
			(layer "B.Fab")
		)
		(fp_line
			(start 0.67945 -0.305054)
			(end 0.12065 -0.305054)
			(stroke
				(width 0.1)
				(type default)
			)
			(layer "B.Fab")
		)
		(pad "1" smd circle
			(at 0.40005 0 90)
			(size 0 0)
			(layers "B.Cu" "B.Mask" "B.Paste")
			(net "SMB_2_BMC_GPU_SDA")
		)
		(pad "2" smd circle
			(at -0.40005 0 90)
			(size 0 0)
			(layers "B.Cu" "B.Mask" "B.Paste")
			(net "P3V3_AUX")
		)
	)
	(footprint ""
		(layer "B.Cu")
		(at 450.84365 -193.99631)
		(property "Reference" "R101"
			(at 0 0 0)
			(layer "B.SilkS")
			(hide yes)
			(effects
				(font
					(size 1.27 1.27)
				)
				(justify mirror)
			)
		)
		(property "Value" ""
			(at 0 0 0)
			(layer "B.Fab")
			(effects
				(font
					(size 1.27 1.27)
				)
				(justify mirror)
			)
		)
		(duplicate_pad_numbers_are_jumpers no)
		(fp_line
			(start -0.7874 -0.4064)
			(end -0.7874 0.4064)
			(stroke
				(width 0.1524)
				(type default)
			)
			(layer "B.SilkS")
		)
		(fp_line
			(start -0.7874 0.4064)
			(end 0.7874 0.4064)
			(stroke
				(width 0.1524)
				(type default)
			)
			(layer "B.SilkS")
		)
		(fp_line
			(start 0.7874 -0.4064)
			(end -0.7874 -0.4064)
			(stroke
				(width 0.1524)
				(type default)
			)
			(layer "B.SilkS")
		)
		(fp_line
			(start 0.7874 0.4064)
			(end 0.7874 -0.4064)
			(stroke
				(width 0.1524)
				(type default)
			)
			(layer "B.SilkS")
		)
		(fp_line
			(start -0.67945 -0.3048)
			(end -0.67945 0.3048)
			(stroke
				(width 0.1)
				(type default)
			)
			(layer "B.Fab")
		)
		(fp_line
			(start -0.67945 0.3048)
			(end -0.120396 0.3048)
			(stroke
				(width 0.1)
				(type default)
			)
			(layer "B.Fab")
		)
		(fp_line
			(start -0.12065 -0.3048)
			(end -0.67945 -0.3048)
			(stroke
				(width 0.1)
				(type default)
			)
			(layer "B.Fab")
		)
		(fp_line
			(start -0.12065 -0.2794)
			(end -0.12065 -0.3048)
			(stroke
				(width 0.1)
				(type default)
			)
			(layer "B.Fab")
		)
		(fp_line
			(start -0.120396 0.2794)
			(end 0.12065 0.2794)
			(stroke
				(width 0.1)
				(type default)
			)
			(layer "B.Fab")
		)
		(fp_line
			(start -0.120396 0.3048)
			(end -0.120396 0.2794)
			(stroke
				(width 0.1)
				(type default)
			)
			(layer "B.Fab")
		)
		(fp_line
			(start 0.12065 -0.305054)
			(end 0.12065 -0.2794)
			(stroke
				(width 0.1)
				(type default)
			)
			(layer "B.Fab")
		)
		(fp_line
			(start 0.12065 -0.2794)
			(end -0.12065 -0.2794)
			(stroke
				(width 0.1)
				(type default)
			)
			(layer "B.Fab")
		)
		(fp_line
			(start 0.12065 0.2794)
			(end 0.12065 0.3048)
			(stroke
				(width 0.1)
				(type default)
			)
			(layer "B.Fab")
		)
		(fp_line
			(start 0.12065 0.3048)
			(end 0.67945 0.3048)
			(stroke
				(width 0.1)
				(type default)
			)
			(layer "B.Fab")
		)
		(fp_line
			(start 0.67945 -0.305054)
			(end 0.12065 -0.305054)
			(stroke
				(width 0.1)
				(type default)
			)
			(layer "B.Fab")
		)
		(fp_line
			(start 0.67945 0.3048)
			(end 0.67945 -0.305054)
			(stroke
				(width 0.1)
				(type default)
			)
			(layer "B.Fab")
		)
		(pad "1" smd circle
			(at 0.40005 0 180)
			(size 0 0)
			(layers "B.Cu" "B.Mask" "B.Paste")
			(net "P3V3")
		)
		(pad "2" smd circle
			(at -0.40005 0 180)
			(size 0 0)
			(layers "B.Cu" "B.Mask" "B.Paste")
			(net "PWRGD_CHL_CPU0_DIMM")
		)
	)
	(footprint ""
		(layer "B.Cu")
		(at 48.0568 -112.800384)
		(property "Reference" "ME16"
			(at 0 0 0)
			(layer "B.SilkS")
			(hide yes)
			(effects
				(font
					(size 1.27 1.27)
				)
				(justify mirror)
			)
		)
		(property "Value" ""
			(at 0 0 0)
			(layer "B.Fab")
			(effects
				(font
					(size 1.27 1.27)
				)
				(justify mirror)
			)
		)
		(duplicate_pad_numbers_are_jumpers no)
		(zone
			(layer "B.Cu")
			(hatch none 0.5)
			(connect_pads
				(clearance 0)
			)
			(min_thickness 0.25)
			(keepout
				(tracks allowed)
				(vias allowed)
				(pads allowed)
				(copperpour allowed)
				(footprints not_allowed)
			)
			(placement
				(enabled no)
				(sheetname "")
			)
			(fill
				(thermal_gap 0.5)
				(thermal_bridge_width 0.5)
				(island_removal_mode 0)
			)
			(polygon
				(pts
					(arc
						(start 58.05678 -112.800384)
						(mid 38.05682 -112.800384)
						(end 58.05678 -112.800384)
					)
				)
			)
		)
	)
	(footprint ""
		(layer "B.Cu")
		(at 373.329454 -254.19431)
		(property "Reference" "C2534"
			(at 0 0 0)
			(layer "B.SilkS")
			(hide yes)
			(effects
				(font
					(size 1.27 1.27)
				)
				(justify mirror)
			)
		)
		(property "Value" ""
			(at 0 0 0)
			(layer "B.Fab")
			(effects
				(font
					(size 1.27 1.27)
				)
				(justify mirror)
			)
		)
		(duplicate_pad_numbers_are_jumpers no)
		(fp_line
			(start -0.7874 -0.4064)
			(end -0.7874 0.4064)
			(stroke
				(width 0.1524)
				(type default)
			)
			(layer "B.SilkS")
		)
		(fp_line
			(start -0.7874 0.4064)
			(end 0.7874 0.4064)
			(stroke
				(width 0.1524)
				(type default)
			)
			(layer "B.SilkS")
		)
		(fp_line
			(start 0.7874 -0.4064)
			(end -0.7874 -0.4064)
			(stroke
				(width 0.1524)
				(type default)
			)
			(layer "B.SilkS")
		)
		(fp_line
			(start 0.7874 0.4064)
			(end 0.7874 -0.4064)
			(stroke
				(width 0.1524)
				(type default)
			)
			(layer "B.SilkS")
		)
		(fp_line
			(start -0.67945 -0.3048)
			(end -0.67945 0.3048)
			(stroke
				(width 0.1)
				(type default)
			)
			(layer "B.Fab")
		)
		(fp_line
			(start -0.67945 0.3048)
			(end -0.120396 0.3048)
			(stroke
				(width 0.1)
				(type default)
			)
			(layer "B.Fab")
		)
		(fp_line
			(start -0.12065 -0.3048)
			(end -0.67945 -0.3048)
			(stroke
				(width 0.1)
				(type default)
			)
			(layer "B.Fab")
		)
		(fp_line
			(start -0.12065 -0.2794)
			(end -0.12065 -0.3048)
			(stroke
				(width 0.1)
				(type default)
			)
			(layer "B.Fab")
		)
		(fp_line
			(start -0.120396 0.2794)
			(end 0.12065 0.2794)
			(stroke
				(width 0.1)
				(type default)
			)
			(layer "B.Fab")
		)
		(fp_line
			(start -0.120396 0.3048)
			(end -0.120396 0.2794)
			(stroke
				(width 0.1)
				(type default)
			)
			(layer "B.Fab")
		)
		(fp_line
			(start 0.12065 -0.305054)
			(end 0.12065 -0.2794)
			(stroke
				(width 0.1)
				(type default)
			)
			(layer "B.Fab")
		)
		(fp_line
			(start 0.12065 -0.2794)
			(end -0.12065 -0.2794)
			(stroke
				(width 0.1)
				(type default)
			)
			(layer "B.Fab")
		)
		(fp_line
			(start 0.12065 0.2794)
			(end 0.12065 0.3048)
			(stroke
				(width 0.1)
				(type default)
			)
			(layer "B.Fab")
		)
		(fp_line
			(start 0.12065 0.3048)
			(end 0.67945 0.3048)
			(stroke
				(width 0.1)
				(type default)
			)
			(layer "B.Fab")
		)
		(fp_line
			(start 0.67945 -0.305054)
			(end 0.12065 -0.305054)
			(stroke
				(width 0.1)
				(type default)
			)
			(layer "B.Fab")
		)
		(fp_line
			(start 0.67945 0.3048)
			(end 0.67945 -0.305054)
			(stroke
				(width 0.1)
				(type default)
			)
			(layer "B.Fab")
		)
		(pad "1" smd circle
			(at 0.40005 0 180)
			(size 0 0)
			(layers "B.Cu" "B.Mask" "B.Paste")
			(net "PVDDCR_SOC_P0")
		)
		(pad "2" smd circle
			(at -0.40005 0 180)
			(size 0 0)
			(layers "B.Cu" "B.Mask" "B.Paste")
			(net "GND")
		)
	)
	(footprint ""
		(layer "B.Cu")
		(at 91.906344 -386.766562 90)
		(property "Reference" "C300"
			(at 0 0 90)
			(layer "B.SilkS")
			(hide yes)
			(effects
				(font
					(size 1.27 1.27)
				)
				(justify mirror)
			)
		)
		(property "Value" ""
			(at 0 0 90)
			(layer "B.Fab")
			(effects
				(font
					(size 1.27 1.27)
				)
				(justify mirror)
			)
		)
		(duplicate_pad_numbers_are_jumpers no)
		(fp_line
			(start 0.299974 -0.150114)
			(end -0.299974 -0.150114)
			(stroke
				(width 0.1)
				(type default)
			)
			(layer "B.Fab")
		)
		(fp_line
			(start -0.299974 -0.150114)
			(end -0.299974 0.150114)
			(stroke
				(width 0.1)
				(type default)
			)
			(layer "B.Fab")
		)
		(fp_line
			(start 0.299974 0.150114)
			(end 0.299974 -0.150114)
			(stroke
				(width 0.1)
				(type default)
			)
			(layer "B.Fab")
		)
		(fp_line
			(start -0.299974 0.150114)
			(end 0.299974 0.150114)
			(stroke
				(width 0.1)
				(type default)
			)
			(layer "B.Fab")
		)
		(pad "1" smd rect
			(at 0.2667 0 270)
			(size 0.3048 0.381)
			(layers "B.Cu" "B.Mask" "B.Paste")
			(net "P0V9_CPU1_RT_2D")
		)
		(pad "2" smd rect
			(at -0.2667 0 270)
			(size 0.3048 0.381)
			(layers "B.Cu" "B.Mask" "B.Paste")
			(net "GND")
		)
	)
	(footprint ""
		(layer "B.Cu")
		(at 316.718188 -396.393162 -90)
		(property "Reference" "C544"
			(at 0 0 90)
			(layer "B.SilkS")
			(hide yes)
			(effects
				(font
					(size 1.27 1.27)
				)
				(justify mirror)
			)
		)
		(property "Value" ""
			(at 0 0 90)
			(layer "B.Fab")
			(effects
				(font
					(size 1.27 1.27)
				)
				(justify mirror)
			)
		)
		(duplicate_pad_numbers_are_jumpers no)
		(fp_line
			(start -0.299974 0.150114)
			(end 0.299974 0.150114)
			(stroke
				(width 0.1)
				(type default)
			)
			(layer "B.Fab")
		)
		(fp_line
			(start 0.299974 0.150114)
			(end 0.299974 -0.150114)
			(stroke
				(width 0.1)
				(type default)
			)
			(layer "B.Fab")
		)
		(fp_line
			(start -0.299974 -0.150114)
			(end -0.299974 0.150114)
			(stroke
				(width 0.1)
				(type default)
			)
			(layer "B.Fab")
		)
		(fp_line
			(start 0.299974 -0.150114)
			(end -0.299974 -0.150114)
			(stroke
				(width 0.1)
				(type default)
			)
			(layer "B.Fab")
		)
		(pad "1" smd rect
			(at 0.2667 0 90)
			(size 0.3048 0.381)
			(layers "B.Cu" "B.Mask" "B.Paste")
			(net "P0V9_CPU0_RT0_2A_2D")
		)
		(pad "2" smd rect
			(at -0.2667 0 90)
			(size 0.3048 0.381)
			(layers "B.Cu" "B.Mask" "B.Paste")
			(net "GND")
		)
	)
)
